(kicad_pcb
	(version 20221018)
	(generator pcbnew)
	(general
    (thickness 1.518)
  )
	(paper "A4")
	(title_block
    (title "Kria K26 Devboard")
    (date "2024-03-26")
    (rev "1.2.5")
    (comment 1 "www.antmicro.com")
    (comment 2 "Antmicro Ltd.")
		(comment 9 "footprints 623-628 of 660")
	)
	(layers
    (0 "F.Cu" mixed)
    (1 "In1.Cu" power)
    (2 "In2.Cu" mixed)
    (3 "In3.Cu" power)
    (4 "In4.Cu" mixed)
    (5 "In5.Cu" power)
    (6 "In6.Cu" mixed)
    (31 "B.Cu" power)
    (32 "B.Adhes" user "B.Adhesive")
    (33 "F.Adhes" user "F.Adhesive")
    (34 "B.Paste" user)
    (35 "F.Paste" user)
    (36 "B.SilkS" user "B.Silkscreen")
    (37 "F.SilkS" user "F.Silkscreen")
    (38 "B.Mask" user)
    (39 "F.Mask" user)
    (40 "Dwgs.User" user "User.Drawings")
    (41 "Cmts.User" user "User.Comments")
    (42 "Eco1.User" user "User.Eco1")
    (43 "Eco2.User" user "User.Eco2")
    (44 "Edge.Cuts" user)
    (45 "Margin" user)
    (46 "B.CrtYd" user "B.Courtyard")
    (47 "F.CrtYd" user "F.Courtyard")
    (48 "B.Fab" user)
    (49 "F.Fab" user)
  )
	(footprint "kria-k26-devboard-footprints:USON-10_2.5x1mm_P0.5mm" (layer "B.Cu")
    (at 174.3 141.9 90)
    (descr "USON-10 2.5x1mm_ Pitch 0.5mm")
    (tags "USON-10 2.5x1mm Pitch 0.5mm")
    (property "Author" "Antmicro")
    (property "License" "Apache-2.0")
    (property "MPN" "TPD4E05U06QDQARQ1")
    (property "Manufacturer" "Texas Instruments")
    (property "Sheetfile" "pmod.kicad_sch")
    (property "Sheetname" "PMOD")
    (property "ki_description" "ESD protection")
    (property "ki_keywords" "SMT, DIODE, IC, TVS, ESD")
    (attr smd)
    (fp_text reference "U14" (at 0.018 1.7 270) (layer "B.SilkS")
        (effects (font (size 0.7 0.7) (thickness 0.15)) (justify left bottom mirror))
    )
    (fp_text value "TPD4E05U06QDQARQ1" (at 0.018 -2.499 270) (layer "B.Fab")
        (effects (font (size 0.7 0.7) (thickness 0.15)) (justify left bottom mirror))
    )
    (fp_text user "${REFERENCE}" (at -0.802 -4.498 270) (layer "B.Fab") hide
        (effects (font (size 0.7 0.7) (thickness 0.15)) (justify left bottom mirror))
    )
    (fp_text user "License: Apache-2.0" (at -0.802 -6.9 270) (layer "B.Fab") hide
        (effects (font (size 0.7 0.7) (thickness 0.15)) (justify left bottom mirror))
    )
    (fp_text user "Author: Antmicro" (at -0.802 -5.7 270) (layer "B.Fab") hide
        (effects (font (size 0.7 0.7) (thickness 0.15)) (justify left bottom mirror))
    )
    (fp_line (start 0.498 -1.398) (end -0.5 -1.398)
      (stroke (width 0.15) (type solid)) (layer "B.SilkS"))
    (fp_line (start 0.498 1.401) (end -0.5 1.401)
      (stroke (width 0.15) (type solid)) (layer "B.SilkS"))
    (fp_circle (center -0.68 1.27) (end -0.63 1.27)
      (stroke (width 0.15) (type solid)) (fill solid) (layer "B.SilkS"))
    (fp_rect (start -0.8 1.5) (end 0.8 -1.499)
      (stroke (width 0.05) (type solid)) (fill none) (layer "B.CrtYd"))
    (fp_line (start -0.5 -1.249) (end 0.498 -1.249)
      (stroke (width 0.15) (type solid)) (layer "B.Fab"))
    (fp_line (start -0.5 1) (end -0.5 -1.249)
      (stroke (width 0.15) (type solid)) (layer "B.Fab"))
    (fp_line (start -0.25 1.25) (end -0.5 1)
      (stroke (width 0.15) (type solid)) (layer "B.Fab"))
    (fp_line (start 0.498 1.25) (end -0.25 1.25)
      (stroke (width 0.15) (type solid)) (layer "B.Fab"))
    (fp_line (start 0.498 1.25) (end 0.498 -1.249)
      (stroke (width 0.15) (type solid)) (layer "B.Fab"))
    (pad "1" smd roundrect (at -0.387 1 180) (size 0.25 0.55) (layers "B.Cu" "B.Paste" "B.Mask") (roundrect_rratio 0.25)
      (net 144 "/PMOD/HDA11") (pintype "passive"))
    (pad "2" smd roundrect (at -0.387 0.5 180) (size 0.25 0.55) (layers "B.Cu" "B.Paste" "B.Mask") (roundrect_rratio 0.25)
      (net 155 "/PMOD/HDA12") (pintype "passive"))
    (pad "3" smd roundrect (at -0.387 0 180) (size 0.4 0.55) (layers "B.Cu" "B.Paste" "B.Mask") (roundrect_rratio 0.25)
      (net 1 "GND") (pintype "power_in"))
    (pad "4" smd roundrect (at -0.387 -0.498 180) (size 0.25 0.55) (layers "B.Cu" "B.Paste" "B.Mask") (roundrect_rratio 0.25)
      (net 156 "/PMOD/HDA13") (pintype "passive"))
    (pad "5" smd roundrect (at -0.387 -0.998 180) (size 0.25 0.55) (layers "B.Cu" "B.Paste" "B.Mask") (roundrect_rratio 0.25)
      (net 157 "/PMOD/HDA14") (pintype "passive"))
    (pad "6" smd roundrect (at 0.385 -0.998 180) (size 0.25 0.55) (layers "B.Cu" "B.Paste" "B.Mask") (roundrect_rratio 0.25)
      (net 157 "/PMOD/HDA14") (pintype "passive"))
    (pad "7" smd roundrect (at 0.385 -0.498 180) (size 0.25 0.55) (layers "B.Cu" "B.Paste" "B.Mask") (roundrect_rratio 0.25)
      (net 156 "/PMOD/HDA13") (pintype "passive"))
    (pad "8" smd roundrect (at 0.385 0 180) (size 0.4 0.55) (layers "B.Cu" "B.Paste" "B.Mask") (roundrect_rratio 0.25)
      (net 1 "GND") (pintype "passive"))
    (pad "9" smd roundrect (at 0.385 0.5 180) (size 0.25 0.55) (layers "B.Cu" "B.Paste" "B.Mask") (roundrect_rratio 0.25)
      (net 155 "/PMOD/HDA12") (pintype "passive"))
    (pad "10" smd roundrect (at 0.385 1 180) (size 0.25 0.55) (layers "B.Cu" "B.Paste" "B.Mask") (roundrect_rratio 0.25)
      (net 144 "/PMOD/HDA11") (pintype "passive"))
  )
	(footprint "kria-k26-devboard-footprints:C_0402_1005Metric" (layer "B.Cu")
    (at 110.675 75.133 90)
    (descr "Capacitor SMD 0402")
    (tags "capacitor SMD 0402")
    (property "Author" "Antmicro")
    (property "Dielectric" "X5R")
    (property "License" "Apache-2.0")
    (property "MPN" "GRM155R61H104KE14D")
    (property "Manufacturer" "Murata")
    (property "Sheetfile" "usb.kicad_sch")
    (property "Sheetname" "USB")
    (property "Val" "100n")
    (property "Voltage" "50V")
    (property "ki_description" " ")
    (attr smd)
    (fp_text reference "C78" (at -0.812 0.34 270) (layer "B.SilkS")
        (effects (font (size 0.7 0.7) (thickness 0.15)) (justify left bottom mirror))
    )
    (fp_text value "C_100n_0402" (at 0 -1.4 270) (layer "B.Fab") hide
        (effects (font (size 0.7 0.7) (thickness 0.15)) (justify left bottom mirror))
    )
    (fp_text user "Author: Antmicro" (at -0.932 -4.17 270) (layer "B.Fab") hide
        (effects (font (size 0.7 0.7) (thickness 0.15)) (justify left bottom mirror))
    )
    (fp_text user "License: Apache-2.0" (at -0.932 -5.17 270) (layer "B.Fab") hide
        (effects (font (size 0.7 0.7) (thickness 0.15)) (justify left bottom mirror))
    )
    (fp_text user "${REFERENCE}" (at -0.932 -3.168 270) (layer "B.Fab") hide
        (effects (font (size 0.7 0.7) (thickness 0.15)) (justify left bottom mirror))
    )
    (fp_rect (start -0.94 0.47) (end 0.94 -0.47)
      (stroke (width 0.05) (type solid)) (fill none) (layer "B.CrtYd"))
    (fp_rect (start -0.499 0.249) (end 0.499 -0.249)
      (stroke (width 0.15) (type solid)) (fill none) (layer "B.Fab"))
    (pad "1" smd roundrect (at -0.484 0 90) (size 0.59 0.64) (layers "B.Cu" "B.Paste" "B.Mask") (roundrect_rratio 0.25)
      (net 65 "/USB/USB3_TX_N") (pintype "passive"))
    (pad "2" smd roundrect (at 0.484 0 90) (size 0.59 0.64) (layers "B.Cu" "B.Paste" "B.Mask") (roundrect_rratio 0.25)
      (net 282 "/USB/USB3_TX_C_N") (pintype "passive"))
  )
	(footprint "kria-k26-devboard-footprints:C_0402_1005Metric" (layer "B.Cu")
    (at 111.62 75.138 90)
    (descr "Capacitor SMD 0402")
    (tags "capacitor SMD 0402")
    (property "Author" "Antmicro")
    (property "Dielectric" "X5R")
    (property "License" "Apache-2.0")
    (property "MPN" "GRM155R61H104KE14D")
    (property "Manufacturer" "Murata")
    (property "Sheetfile" "usb.kicad_sch")
    (property "Sheetname" "USB")
    (property "Val" "100n")
    (property "Voltage" "50V")
    (property "ki_description" " ")
    (attr smd)
    (fp_text reference "C79" (at -0.812 0.34 270) (layer "B.SilkS")
        (effects (font (size 0.7 0.7) (thickness 0.15)) (justify left bottom mirror))
    )
    (fp_text value "C_100n_0402" (at 0 -1.4 270) (layer "B.Fab") hide
        (effects (font (size 0.7 0.7) (thickness 0.15)) (justify left bottom mirror))
    )
    (fp_text user "License: Apache-2.0" (at -0.932 -5.17 270) (layer "B.Fab") hide
        (effects (font (size 0.7 0.7) (thickness 0.15)) (justify left bottom mirror))
    )
    (fp_text user "Author: Antmicro" (at -0.932 -4.17 270) (layer "B.Fab") hide
        (effects (font (size 0.7 0.7) (thickness 0.15)) (justify left bottom mirror))
    )
    (fp_text user "${REFERENCE}" (at -0.932 -3.168 270) (layer "B.Fab") hide
        (effects (font (size 0.7 0.7) (thickness 0.15)) (justify left bottom mirror))
    )
    (fp_rect (start -0.94 0.47) (end 0.94 -0.47)
      (stroke (width 0.05) (type solid)) (fill none) (layer "B.CrtYd"))
    (fp_rect (start -0.499 0.249) (end 0.499 -0.249)
      (stroke (width 0.15) (type solid)) (fill none) (layer "B.Fab"))
    (pad "1" smd roundrect (at -0.484 0 90) (size 0.59 0.64) (layers "B.Cu" "B.Paste" "B.Mask") (roundrect_rratio 0.25)
      (net 66 "/USB/USB3_TX_P") (pintype "passive"))
    (pad "2" smd roundrect (at 0.484 0 90) (size 0.59 0.64) (layers "B.Cu" "B.Paste" "B.Mask") (roundrect_rratio 0.25)
      (net 283 "/USB/USB3_TX_C_P") (pintype "passive"))
  )
	(footprint "kria-k26-devboard-footprints:USON-10_2.5x1mm_P0.5mm" (layer "B.Cu")
    (at 129.75 73.25 -90)
    (descr "USON-10 2.5x1mm_ Pitch 0.5mm")
    (tags "USON-10 2.5x1mm Pitch 0.5mm")
    (property "Author" "Antmicro")
    (property "License" "Apache-2.0")
    (property "MPN" "TPD4E05U06QDQARQ1")
    (property "Manufacturer" "Texas Instruments")
    (property "Sheetfile" "usb.kicad_sch")
    (property "Sheetname" "USB")
    (property "ki_description" "ESD protection")
    (property "ki_keywords" "SMT, DIODE, IC, TVS, ESD")
    (attr smd)
    (fp_text reference "U22" (at 0.018 1.7 90) (layer "B.SilkS")
        (effects (font (size 0.7 0.7) (thickness 0.15)) (justify left bottom mirror))
    )
    (fp_text value "TPD4E05U06QDQARQ1" (at 0.018 -2.499 90) (layer "B.Fab")
        (effects (font (size 0.7 0.7) (thickness 0.15)) (justify left bottom mirror))
    )
    (fp_text user "License: Apache-2.0" (at -0.802 -6.9 90) (layer "B.Fab") hide
        (effects (font (size 0.7 0.7) (thickness 0.15)) (justify left bottom mirror))
    )
    (fp_text user "${REFERENCE}" (at -0.802 -4.498 90) (layer "B.Fab") hide
        (effects (font (size 0.7 0.7) (thickness 0.15)) (justify left bottom mirror))
    )
    (fp_text user "Author: Antmicro" (at -0.802 -5.7 90) (layer "B.Fab") hide
        (effects (font (size 0.7 0.7) (thickness 0.15)) (justify left bottom mirror))
    )
    (fp_line (start 0.498 -1.398) (end -0.5 -1.398)
      (stroke (width 0.15) (type solid)) (layer "B.SilkS"))
    (fp_line (start 0.498 1.401) (end -0.5 1.401)
      (stroke (width 0.15) (type solid)) (layer "B.SilkS"))
    (fp_circle (center -0.68 1.27) (end -0.63 1.27)
      (stroke (width 0.15) (type solid)) (fill solid) (layer "B.SilkS"))
    (fp_rect (start -0.8 1.5) (end 0.8 -1.499)
      (stroke (width 0.05) (type solid)) (fill none) (layer "B.CrtYd"))
    (fp_line (start -0.5 -1.249) (end 0.498 -1.249)
      (stroke (width 0.15) (type solid)) (layer "B.Fab"))
    (fp_line (start -0.5 1) (end -0.5 -1.249)
      (stroke (width 0.15) (type solid)) (layer "B.Fab"))
    (fp_line (start -0.25 1.25) (end -0.5 1)
      (stroke (width 0.15) (type solid)) (layer "B.Fab"))
    (fp_line (start 0.498 1.25) (end -0.25 1.25)
      (stroke (width 0.15) (type solid)) (layer "B.Fab"))
    (fp_line (start 0.498 1.25) (end 0.498 -1.249)
      (stroke (width 0.15) (type solid)) (layer "B.Fab"))
    (pad "1" smd roundrect (at -0.387 1) (size 0.25 0.55) (layers "B.Cu" "B.Paste" "B.Mask") (roundrect_rratio 0.25)
      (net 83 "/USB/USB1_RX_N") (pintype "passive"))
    (pad "2" smd roundrect (at -0.387 0.5) (size 0.25 0.55) (layers "B.Cu" "B.Paste" "B.Mask") (roundrect_rratio 0.25)
      (net 84 "/USB/USB1_RX_P") (pintype "passive"))
    (pad "3" smd roundrect (at -0.387 0) (size 0.4 0.55) (layers "B.Cu" "B.Paste" "B.Mask") (roundrect_rratio 0.25)
      (net 1 "GND") (pintype "power_in"))
    (pad "4" smd roundrect (at -0.387 -0.498) (size 0.25 0.55) (layers "B.Cu" "B.Paste" "B.Mask") (roundrect_rratio 0.25)
      (net 278 "/USB/USB1_TX_C_N") (pintype "passive"))
    (pad "5" smd roundrect (at -0.387 -0.998) (size 0.25 0.55) (layers "B.Cu" "B.Paste" "B.Mask") (roundrect_rratio 0.25)
      (net 279 "/USB/USB1_TX_C_P") (pintype "passive"))
    (pad "6" smd roundrect (at 0.385 -0.998) (size 0.25 0.55) (layers "B.Cu" "B.Paste" "B.Mask") (roundrect_rratio 0.25)
      (net 279 "/USB/USB1_TX_C_P") (pintype "passive"))
    (pad "7" smd roundrect (at 0.385 -0.498) (size 0.25 0.55) (layers "B.Cu" "B.Paste" "B.Mask") (roundrect_rratio 0.25)
      (net 278 "/USB/USB1_TX_C_N") (pintype "passive"))
    (pad "8" smd roundrect (at 0.385 0) (size 0.4 0.55) (layers "B.Cu" "B.Paste" "B.Mask") (roundrect_rratio 0.25)
      (net 1 "GND") (pintype "passive"))
    (pad "9" smd roundrect (at 0.385 0.5) (size 0.25 0.55) (layers "B.Cu" "B.Paste" "B.Mask") (roundrect_rratio 0.25)
      (net 84 "/USB/USB1_RX_P") (pintype "passive"))
    (pad "10" smd roundrect (at 0.385 1) (size 0.25 0.55) (layers "B.Cu" "B.Paste" "B.Mask") (roundrect_rratio 0.25)
      (net 83 "/USB/USB1_RX_N") (pintype "passive"))
  )
	(footprint "kria-k26-devboard-footprints:USON-10_2.5x1mm_P0.5mm" (layer "B.Cu")
    (at 110.4 73.3 -90)
    (descr "USON-10 2.5x1mm_ Pitch 0.5mm")
    (tags "USON-10 2.5x1mm Pitch 0.5mm")
    (property "Author" "Antmicro")
    (property "License" "Apache-2.0")
    (property "MPN" "TPD4E05U06QDQARQ1")
    (property "Manufacturer" "Texas Instruments")
    (property "Sheetfile" "usb.kicad_sch")
    (property "Sheetname" "USB")
    (property "ki_description" "ESD protection")
    (property "ki_keywords" "SMT, DIODE, IC, TVS, ESD")
    (attr smd)
    (fp_text reference "U28" (at 0.018 1.7 90) (layer "B.SilkS")
        (effects (font (size 0.7 0.7) (thickness 0.15)) (justify left bottom mirror))
    )
    (fp_text value "TPD4E05U06QDQARQ1" (at 0.018 -2.499 90) (layer "B.Fab")
        (effects (font (size 0.7 0.7) (thickness 0.15)) (justify left bottom mirror))
    )
    (fp_text user "${REFERENCE}" (at -0.802 -4.498 90) (layer "B.Fab") hide
        (effects (font (size 0.7 0.7) (thickness 0.15)) (justify left bottom mirror))
    )
    (fp_text user "License: Apache-2.0" (at -0.802 -6.9 90) (layer "B.Fab") hide
        (effects (font (size 0.7 0.7) (thickness 0.15)) (justify left bottom mirror))
    )
    (fp_text user "Author: Antmicro" (at -0.802 -5.7 90) (layer "B.Fab") hide
        (effects (font (size 0.7 0.7) (thickness 0.15)) (justify left bottom mirror))
    )
    (fp_line (start 0.498 -1.398) (end -0.5 -1.398)
      (stroke (width 0.15) (type solid)) (layer "B.SilkS"))
    (fp_line (start 0.498 1.401) (end -0.5 1.401)
      (stroke (width 0.15) (type solid)) (layer "B.SilkS"))
    (fp_circle (center -0.68 1.27) (end -0.63 1.27)
      (stroke (width 0.15) (type solid)) (fill solid) (layer "B.SilkS"))
    (fp_rect (start -0.8 1.5) (end 0.8 -1.499)
      (stroke (width 0.05) (type solid)) (fill none) (layer "B.CrtYd"))
    (fp_line (start -0.5 -1.249) (end 0.498 -1.249)
      (stroke (width 0.15) (type solid)) (layer "B.Fab"))
    (fp_line (start -0.5 1) (end -0.5 -1.249)
      (stroke (width 0.15) (type solid)) (layer "B.Fab"))
    (fp_line (start -0.25 1.25) (end -0.5 1)
      (stroke (width 0.15) (type solid)) (layer "B.Fab"))
    (fp_line (start 0.498 1.25) (end -0.25 1.25)
      (stroke (width 0.15) (type solid)) (layer "B.Fab"))
    (fp_line (start 0.498 1.25) (end 0.498 -1.249)
      (stroke (width 0.15) (type solid)) (layer "B.Fab"))
    (pad "1" smd roundrect (at -0.387 1) (size 0.25 0.55) (layers "B.Cu" "B.Paste" "B.Mask") (roundrect_rratio 0.25)
      (net 79 "/USB/USB3_RX_N") (pintype "passive"))
    (pad "2" smd roundrect (at -0.387 0.5) (size 0.25 0.55) (layers "B.Cu" "B.Paste" "B.Mask") (roundrect_rratio 0.25)
      (net 80 "/USB/USB3_RX_P") (pintype "passive"))
    (pad "3" smd roundrect (at -0.387 0) (size 0.4 0.55) (layers "B.Cu" "B.Paste" "B.Mask") (roundrect_rratio 0.25)
      (net 1 "GND") (pintype "power_in"))
    (pad "4" smd roundrect (at -0.387 -0.498) (size 0.25 0.55) (layers "B.Cu" "B.Paste" "B.Mask") (roundrect_rratio 0.25)
      (net 282 "/USB/USB3_TX_C_N") (pintype "passive"))
    (pad "5" smd roundrect (at -0.387 -0.998) (size 0.25 0.55) (layers "B.Cu" "B.Paste" "B.Mask") (roundrect_rratio 0.25)
      (net 283 "/USB/USB3_TX_C_P") (pintype "passive"))
    (pad "6" smd roundrect (at 0.385 -0.998) (size 0.25 0.55) (layers "B.Cu" "B.Paste" "B.Mask") (roundrect_rratio 0.25)
      (net 283 "/USB/USB3_TX_C_P") (pintype "passive"))
    (pad "7" smd roundrect (at 0.385 -0.498) (size 0.25 0.55) (layers "B.Cu" "B.Paste" "B.Mask") (roundrect_rratio 0.25)
      (net 282 "/USB/USB3_TX_C_N") (pintype "passive"))
    (pad "8" smd roundrect (at 0.385 0) (size 0.4 0.55) (layers "B.Cu" "B.Paste" "B.Mask") (roundrect_rratio 0.25)
      (net 1 "GND") (pintype "passive"))
    (pad "9" smd roundrect (at 0.385 0.5) (size 0.25 0.55) (layers "B.Cu" "B.Paste" "B.Mask") (roundrect_rratio 0.25)
      (net 80 "/USB/USB3_RX_P") (pintype "passive"))
    (pad "10" smd roundrect (at 0.385 1) (size 0.25 0.55) (layers "B.Cu" "B.Paste" "B.Mask") (roundrect_rratio 0.25)
      (net 79 "/USB/USB3_RX_N") (pintype "passive"))
  )
	(footprint "kria-k26-devboard-footprints:C_0603_1608Metric" (layer "B.Cu")
    (at 152 107.15)
    (descr "Capacitor SMD 0603")
    (tags "capacitor 0603")
    (property "Author" "Antmicro")
    (property "Dielectric" "")
    (property "License" "Apache-2.0")
    (property "MPN" "CL10A105KA8NNNC")
    (property "Manufacturer" "Samsung")
    (property "Sheetfile" "debug.kicad_sch")
    (property "Sheetname" "Debug and JTAG")
    (property "Val" "1u/25V")
    (property "Voltage" "")
    (property "ki_description" " ")
    (attr smd)
    (fp_text reference "C158" (at 4.03 0.35 180) (layer "B.SilkS")
        (effects (font (size 0.7 0.7) (thickness 0.15)) (justify left bottom mirror))
    )
    (fp_text value "C_1u_25V_0603" (at 0 -1.6 180) (layer "B.Fab") hide
        (effects (font (size 0.7 0.7) (thickness 0.15)) (justify left bottom mirror))
    )
    (fp_text user "${REFERENCE}" (at -1.682 -3.895 180) (layer "B.Fab") hide
        (effects (font (size 0.7 0.7) (thickness 0.15)) (justify left bottom mirror))
    )
    (fp_text user "Author: Antmicro" (at -1.682 -4.894 180) (layer "B.Fab") hide
        (effects (font (size 0.7 0.7) (thickness 0.15)) (justify left bottom mirror))
    )
    (fp_text user "License: Apache-2.0" (at -1.682 -5.895 180) (layer "B.Fab") hide
        (effects (font (size 0.7 0.7) (thickness 0.15)) (justify left bottom mirror))
    )
    (fp_line (start -0.3 -0.3) (end 0.3 -0.3)
      (stroke (width 0.15) (type solid)) (layer "B.SilkS"))
    (fp_line (start -0.3 0.3) (end 0.3 0.3)
      (stroke (width 0.15) (type solid)) (layer "B.SilkS"))
    (fp_rect (start -1.24 0.7) (end 1.24 -0.7)
      (stroke (width 0.05) (type solid)) (fill none) (layer "B.CrtYd"))
    (fp_rect (start -0.8 0.4) (end 0.8 -0.4)
      (stroke (width 0.15) (type solid)) (fill none) (layer "B.Fab"))
    (pad "1" smd roundrect (at -0.7 0) (size 0.6 0.8) (layers "B.Cu" "B.Paste" "B.Mask") (roundrect_rratio 0.2)
      (net 313 "/Debug and JTAG/USB_VBUS") (pintype "passive"))
    (pad "2" smd roundrect (at 0.7 0) (size 0.6 0.8) (layers "B.Cu" "B.Paste" "B.Mask") (roundrect_rratio 0.2)
      (net 1 "GND") (pintype "passive"))
  )
)
